# T6G (Grand Teton) — schematic netlist excerpt (pin names and nets, part order shuffled) for the footprints in the layout excerpt that follows; sources: Cadence DE-HDL packaged netlist, KiCad conversion of 04192023_DAF0TMB3IC0_F0TG_MB_C_brd_V02_OCP.brd

C2279  Q_CAP  22UF 4V 20% X6S  pkg C0402  page 72 : A = PVDD11_S3_P1 ; B = GND
PC375  Q_CAP  0.1UF 25V 10% X7R  pkg 0402  page 218 : A = P12V_AUX ; B = GND

(kicad_pcb
	(version 20260206)
	(generator "pcbnew")
	(generator_version "10.0")
	(general
		(thickness 1.6)
		(legacy_teardrops no)
	)
	(paper "A4")
	(title_block
		(title "04192023_DAF0TMB3IC0_F0TG_MB_C_brd_V02_OCP.brd")
		(comment 1 "Grand Teton / footprints 4358-4359 of 8354")
	)
	(layers
		(0 "F.Cu" signal "TOP")
		(4 "In1.Cu" signal "GND")
		(6 "In2.Cu" signal "IN1")
		(8 "In3.Cu" signal "GND1")
		(10 "In4.Cu" signal "IN2")
		(12 "In5.Cu" signal "GND2")
		(14 "In6.Cu" signal "IN3")
		(16 "In7.Cu" signal "GND3")
		(18 "In8.Cu" signal "VCC")
		(20 "In9.Cu" signal "VCC1")
		(22 "In10.Cu" signal "GND4")
		(24 "In11.Cu" signal "IN4")
		(26 "In12.Cu" signal "GND5")
		(28 "In13.Cu" signal "IN5")
		(30 "In14.Cu" signal "GND6")
		(32 "In15.Cu" signal "IN6")
		(34 "In16.Cu" signal "GND7")
		(2 "B.Cu" signal "BOTTOM")
		(9 "F.Adhes" user "F.Adhesive")
		(11 "B.Adhes" user "B.Adhesive")
		(13 "F.Paste" user "Package Geometry/Pastemask Top")
		(15 "B.Paste" user "Package Geometry/Pastemask Bottom")
		(5 "F.SilkS" user "Ref Des/Silkscreen Top")
		(7 "B.SilkS" user "Ref Des/Silkscreen Bottom")
		(1 "F.Mask" user "Board Geometry/Soldermask Top")
		(3 "B.Mask" user "Board Geometry/Soldermask Bottom")
		(17 "Dwgs.User" user "User.Drawings")
		(19 "Cmts.User" user "User.Comments")
		(21 "Eco1.User" user "User.Eco1")
		(23 "Eco2.User" user "User.Eco2")
		(25 "Edge.Cuts" user "Board Geometry/Outline")
		(27 "Margin" user)
		(31 "F.CrtYd" user "Package Geometry/Place Bound Top")
		(29 "B.CrtYd" user "Package Geometry/Place Bound Bottom")
		(35 "F.Fab" user "Ref Des/Assembly Top")
		(33 "B.Fab" user "Ref Des/Assembly Bottom")
	)
	(footprint ""
		(layer "F.Cu")
		(at 113.105946 -259.845302)
		(property "Reference" "C2279"
			(at 0 0 0)
			(layer "F.SilkS")
			(hide yes)
			(effects
				(font
					(size 1.27 1.27)
				)
			)
		)
		(property "Value" ""
			(at 0 0 0)
			(layer "F.Fab")
			(effects
				(font
					(size 1.27 1.27)
				)
			)
		)
		(duplicate_pad_numbers_are_jumpers no)
		(fp_line
			(start -0.7874 -0.4064)
			(end 0.7874 -0.4064)
			(stroke
				(width 0.1524)
				(type default)
			)
			(layer "F.SilkS")
		)
		(fp_line
			(start -0.7874 0.4064)
			(end -0.7874 -0.4064)
			(stroke
				(width 0.1524)
				(type default)
			)
			(layer "F.SilkS")
		)
		(fp_line
			(start 0.7874 -0.4064)
			(end 0.7874 0.4064)
			(stroke
				(width 0.1524)
				(type default)
			)
			(layer "F.SilkS")
		)
		(fp_line
			(start 0.7874 0.4064)
			(end -0.7874 0.4064)
			(stroke
				(width 0.1524)
				(type default)
			)
			(layer "F.SilkS")
		)
		(fp_line
			(start -0.67945 -0.305054)
			(end -0.12065 -0.305054)
			(stroke
				(width 0.1)
				(type default)
			)
			(layer "F.Fab")
		)
		(fp_line
			(start -0.67945 0.3048)
			(end -0.67945 -0.305054)
			(stroke
				(width 0.1)
				(type default)
			)
			(layer "F.Fab")
		)
		(fp_line
			(start -0.12065 -0.305054)
			(end -0.12065 -0.2794)
			(stroke
				(width 0.1)
				(type default)
			)
			(layer "F.Fab")
		)
		(fp_line
			(start -0.12065 -0.2794)
			(end 0.12065 -0.2794)
			(stroke
				(width 0.1)
				(type default)
			)
			(layer "F.Fab")
		)
		(fp_line
			(start -0.12065 0.2794)
			(end -0.12065 0.3048)
			(stroke
				(width 0.1)
				(type default)
			)
			(layer "F.Fab")
		)
		(fp_line
			(start -0.12065 0.3048)
			(end -0.67945 0.3048)
			(stroke
				(width 0.1)
				(type default)
			)
			(layer "F.Fab")
		)
		(fp_line
			(start 0.120396 0.2794)
			(end -0.12065 0.2794)
			(stroke
				(width 0.1)
				(type default)
			)
			(layer "F.Fab")
		)
		(fp_line
			(start 0.120396 0.3048)
			(end 0.120396 0.2794)
			(stroke
				(width 0.1)
				(type default)
			)
			(layer "F.Fab")
		)
		(fp_line
			(start 0.12065 -0.3048)
			(end 0.67945 -0.3048)
			(stroke
				(width 0.1)
				(type default)
			)
			(layer "F.Fab")
		)
		(fp_line
			(start 0.12065 -0.2794)
			(end 0.12065 -0.3048)
			(stroke
				(width 0.1)
				(type default)
			)
			(layer "F.Fab")
		)
		(fp_line
			(start 0.67945 -0.3048)
			(end 0.67945 0.3048)
			(stroke
				(width 0.1)
				(type default)
			)
			(layer "F.Fab")
		)
		(fp_line
			(start 0.67945 0.3048)
			(end 0.120396 0.3048)
			(stroke
				(width 0.1)
				(type default)
			)
			(layer "F.Fab")
		)
		(pad "1" smd circle
			(at -0.40005 0)
			(size 0 0)
			(layers "F.Cu" "F.Mask" "F.Paste")
			(net "PVDD11_S3_P1")
		)
		(pad "2" smd circle
			(at 0.40005 0)
			(size 0 0)
			(layers "F.Cu" "F.Mask" "F.Paste")
			(net "GND")
		)
	)
	(footprint ""
		(layer "F.Cu")
		(at 94.681548 -352.475038)
		(property "Reference" "PC375"
			(at 0 0 0)
			(layer "F.SilkS")
			(hide yes)
			(effects
				(font
					(size 1.27 1.27)
				)
			)
		)
		(property "Value" ""
			(at 0 0 0)
			(layer "F.Fab")
			(effects
				(font
					(size 1.27 1.27)
				)
			)
		)
		(duplicate_pad_numbers_are_jumpers no)
		(fp_line
			(start -0.7874 -0.4064)
			(end 0.7874 -0.4064)
			(stroke
				(width 0.1524)
				(type default)
			)
			(layer "F.SilkS")
		)
		(fp_line
			(start -0.7874 0.4064)
			(end -0.7874 -0.4064)
			(stroke
				(width 0.1524)
				(type default)
			)
			(layer "F.SilkS")
		)
		(fp_line
			(start 0.7874 -0.4064)
			(end 0.7874 0.4064)
			(stroke
				(width 0.1524)
				(type default)
			)
			(layer "F.SilkS")
		)
		(fp_line
			(start 0.7874 0.4064)
			(end -0.7874 0.4064)
			(stroke
				(width 0.1524)
				(type default)
			)
			(layer "F.SilkS")
		)
		(fp_line
			(start -0.67945 -0.305054)
			(end -0.12065 -0.305054)
			(stroke
				(width 0.1)
				(type default)
			)
			(layer "F.Fab")
		)
		(fp_line
			(start -0.67945 0.3048)
			(end -0.67945 -0.305054)
			(stroke
				(width 0.1)
				(type default)
			)
			(layer "F.Fab")
		)
		(fp_line
			(start -0.12065 -0.305054)
			(end -0.12065 -0.2794)
			(stroke
				(width 0.1)
				(type default)
			)
			(layer "F.Fab")
		)
		(fp_line
			(start -0.12065 -0.2794)
			(end 0.12065 -0.2794)
			(stroke
				(width 0.1)
				(type default)
			)
			(layer "F.Fab")
		)
		(fp_line
			(start -0.12065 0.2794)
			(end -0.12065 0.3048)
			(stroke
				(width 0.1)
				(type default)
			)
			(layer "F.Fab")
		)
		(fp_line
			(start -0.12065 0.3048)
			(end -0.67945 0.3048)
			(stroke
				(width 0.1)
				(type default)
			)
			(layer "F.Fab")
		)
		(fp_line
			(start 0.120396 0.2794)
			(end -0.12065 0.2794)
			(stroke
				(width 0.1)
				(type default)
			)
			(layer "F.Fab")
		)
		(fp_line
			(start 0.120396 0.3048)
			(end 0.120396 0.2794)
			(stroke
				(width 0.1)
				(type default)
			)
			(layer "F.Fab")
		)
		(fp_line
			(start 0.12065 -0.3048)
			(end 0.67945 -0.3048)
			(stroke
				(width 0.1)
				(type default)
			)
			(layer "F.Fab")
		)
		(fp_line
			(start 0.12065 -0.2794)
			(end 0.12065 -0.3048)
			(stroke
				(width 0.1)
				(type default)
			)
			(layer "F.Fab")
		)
		(fp_line
			(start 0.67945 -0.3048)
			(end 0.67945 0.3048)
			(stroke
				(width 0.1)
				(type default)
			)
			(layer "F.Fab")
		)
		(fp_line
			(start 0.67945 0.3048)
			(end 0.120396 0.3048)
			(stroke
				(width 0.1)
				(type default)
			)
			(layer "F.Fab")
		)
		(pad "1" smd circle
			(at -0.40005 0)
			(size 0 0)
			(layers "F.Cu" "F.Mask" "F.Paste")
			(net "P12V_AUX")
		)
		(pad "2" smd circle
			(at 0.40005 0)
			(size 0 0)
			(layers "F.Cu" "F.Mask" "F.Paste")
			(net "GND")
		)
	)
)
